(kicad_pcb
	(version 20260206)
	(generator "pcbnew")
	(generator_version "10.0")
	(general
		(thickness 1.6)
		(legacy_teardrops no)
	)
	(paper "A4")
	(title_block
		(title "Bryce Canyon_F.DPB_16315-1-OCP.brd")
		(comment 1 "Bryce Canyon / footprint 993 of 2223 (SAS1), pads 1-69 of 342")
	)
	(layers
		(0 "F.Cu" signal "TOP")
		(4 "In1.Cu" signal "L2GND")
		(6 "In2.Cu" signal "L3")
		(8 "In3.Cu" signal "L4GND")
		(10 "In4.Cu" signal "L5")
		(12 "In5.Cu" signal "L6VCC")
		(14 "In6.Cu" signal "L7VCC")
		(16 "In7.Cu" signal "L8")
		(18 "In8.Cu" signal "L9GND")
		(20 "In9.Cu" signal "L10")
		(22 "In10.Cu" signal "L11GND")
		(2 "B.Cu" signal "BOTTOM")
		(9 "F.Adhes" user "F.Adhesive")
		(11 "B.Adhes" user "B.Adhesive")
		(13 "F.Paste" user "Package Geometry/Pastemask Top")
		(15 "B.Paste" user "Package Geometry/Pastemask Bottom")
		(5 "F.SilkS" user "Ref Des/Silkscreen Top")
		(7 "B.SilkS" user "Ref Des/Silkscreen Bottom")
		(1 "F.Mask" user "Board Geometry/Soldermask Top")
		(3 "B.Mask" user "Board Geometry/Soldermask Bottom")
		(17 "Dwgs.User" user "User.Drawings")
		(19 "Cmts.User" user "User.Comments")
		(21 "Eco1.User" user "User.Eco1")
		(23 "Eco2.User" user "User.Eco2")
		(25 "Edge.Cuts" user "Board Geometry/Outline")
		(27 "Margin" user)
		(31 "F.CrtYd" user "Package Geometry/Place Bound Top")
		(29 "B.CrtYd" user "Package Geometry/Place Bound Bottom")
		(35 "F.Fab" user "Ref Des/Assembly Top")
		(33 "B.Fab" user "Ref Des/Assembly Bottom")
	)
	(footprint ""
		(layer "F.Cu")
		(at 287.83661 -357.705152 -90)
		(property "Reference" "SAS1"
			(at 0 0 270)
			(layer "F.SilkS")
			(hide yes)
			(effects
				(font
					(size 1.27 1.27)
				)
			)
		)
		(property "Value" "AMP-CONN342-10R-2-GP"
			(at 20.955 -16.7386 270)
			(unlocked yes)
			(layer "F.Fab")
			(hide yes)
			(effects
				(font
					(size 1.016 1.016)
					(thickness 0.1524)
				)
			)
		)
		(property "Device Type" "PREFIT-342P-668151H483"
			(at 20.955 -18.2626 270)
			(unlocked yes)
			(layer "F.Fab")
			(hide yes)
			(effects
				(font
					(size 1.016 1.016)
					(thickness 0.1524)
				)
			)
		)
		(duplicate_pad_numbers_are_jumpers no)
		(pad "A1" thru_hole circle
			(at 0 0 270)
			(size 0.762 0.762)
			(drill 0.359918)
			(layers "*.Cu" "*.Mask")
			(remove_unused_layers no)
			(net "PHY_DRV_A_TO_SCC_A_0_DN")
			(clearance 0.1651)
			(thermal_gap 0.1651)
		)
		(pad "A2" thru_hole circle
			(at 1.800098 0.999998 270)
			(size 0.762 0.762)
			(drill 0.359918)
			(layers "*.Cu" "*.Mask")
			(remove_unused_layers no)
			(net "PHY_DRV_A_TO_SCC_A_1_DN")
			(clearance 0.1651)
			(thermal_gap 0.1651)
		)
		(pad "A3" thru_hole circle
			(at 3.599942 0 270)
			(size 0.762 0.762)
			(drill 0.359918)
			(layers "*.Cu" "*.Mask")
			(remove_unused_layers no)
			(net "PHY_DRV_A_TO_SCC_A_2_DN")
			(clearance 0.1651)
			(thermal_gap 0.1651)
		)
		(pad "A4" thru_hole circle
			(at 5.40004 0.999998 270)
			(size 0.762 0.762)
			(drill 0.359918)
			(layers "*.Cu" "*.Mask")
			(remove_unused_layers no)
			(net "PHY_DRV_A_TO_SCC_A_3_DN")
			(clearance 0.1651)
			(thermal_gap 0.1651)
		)
		(pad "A5" thru_hole circle
			(at 7.199884 0 270)
			(size 0.762 0.762)
			(drill 0.359918)
			(layers "*.Cu" "*.Mask")
			(remove_unused_layers no)
			(net "PHY_DRV_A_TO_SCC_A_4_DN")
			(clearance 0.1651)
			(thermal_gap 0.1651)
		)
		(pad "A6" thru_hole circle
			(at 8.999982 0.999998 270)
			(size 0.762 0.762)
			(drill 0.359918)
			(layers "*.Cu" "*.Mask")
			(remove_unused_layers no)
			(net "PHY_DRV_A_TO_SCC_A_5_DN")
			(clearance 0.1651)
			(thermal_gap 0.1651)
		)
		(pad "A7" thru_hole circle
			(at 10.80008 0 270)
			(size 0.762 0.762)
			(drill 0.359918)
			(layers "*.Cu" "*.Mask")
			(remove_unused_layers no)
			(net "PHY_DRV_A_TO_SCC_A_11_DN")
			(clearance 0.1651)
			(thermal_gap 0.1651)
		)
		(pad "A8" thru_hole circle
			(at 12.599924 0.999998 270)
			(size 0.762 0.762)
			(drill 0.359918)
			(layers "*.Cu" "*.Mask")
			(remove_unused_layers no)
			(net "PHY_DRV_A_TO_SCC_A_10_DN")
			(clearance 0.1651)
			(thermal_gap 0.1651)
		)
		(pad "A9" thru_hole circle
			(at 14.400022 0 270)
			(size 0.762 0.762)
			(drill 0.359918)
			(layers "*.Cu" "*.Mask")
			(remove_unused_layers no)
			(net "PHY_DRV_A_TO_SCC_A_9_DN")
			(clearance 0.1651)
			(thermal_gap 0.1651)
		)
		(pad "A10" thru_hole circle
			(at 16.20012 0.999998 270)
			(size 0.762 0.762)
			(drill 0.359918)
			(layers "*.Cu" "*.Mask")
			(remove_unused_layers no)
			(net "PHY_DRV_A_TO_SCC_A_8_DN")
			(clearance 0.1651)
			(thermal_gap 0.1651)
		)
		(pad "A11" thru_hole circle
			(at 17.999964 0 270)
			(size 0.762 0.762)
			(drill 0.359918)
			(layers "*.Cu" "*.Mask")
			(remove_unused_layers no)
			(net "PHY_DRV_A_TO_SCC_A_7_DN")
			(clearance 0.1651)
			(thermal_gap 0.1651)
		)
		(pad "A12" thru_hole circle
			(at 19.800062 0.999998 270)
			(size 0.762 0.762)
			(drill 0.359918)
			(layers "*.Cu" "*.Mask")
			(remove_unused_layers no)
			(net "PHY_DRV_A_TO_SCC_A_6_DN")
			(clearance 0.1651)
			(thermal_gap 0.1651)
		)
		(pad "A13" thru_hole circle
			(at 21.599906 0 270)
			(size 0.762 0.762)
			(drill 0.359918)
			(layers "*.Cu" "*.Mask")
			(remove_unused_layers no)
			(net "PHY_DRV_A_TO_SCC_A_12_DN")
			(clearance 0.1651)
			(thermal_gap 0.1651)
		)
		(pad "A14" thru_hole circle
			(at 23.400004 0.999998 270)
			(size 0.762 0.762)
			(drill 0.359918)
			(layers "*.Cu" "*.Mask")
			(remove_unused_layers no)
			(net "PHY_DRV_A_TO_SCC_A_13_DN")
			(clearance 0.1651)
			(thermal_gap 0.1651)
		)
		(pad "A15" thru_hole circle
			(at 25.200102 0 270)
			(size 0.762 0.762)
			(drill 0.359918)
			(layers "*.Cu" "*.Mask")
			(remove_unused_layers no)
			(net "PHY_DRV_A_TO_SCC_A_14_DN")
			(clearance 0.1651)
			(thermal_gap 0.1651)
		)
		(pad "A16" thru_hole circle
			(at 26.999946 0.999998 270)
			(size 0.762 0.762)
			(drill 0.359918)
			(layers "*.Cu" "*.Mask")
			(remove_unused_layers no)
			(net "PHY_DRV_A_TO_SCC_A_15_DN")
			(clearance 0.1651)
			(thermal_gap 0.1651)
		)
		(pad "A17" thru_hole circle
			(at 28.800044 0 270)
			(size 0.762 0.762)
			(drill 0.359918)
			(layers "*.Cu" "*.Mask")
			(remove_unused_layers no)
			(net "PHY_DRV_A_TO_SCC_A_16_DN")
			(clearance 0.1651)
			(thermal_gap 0.1651)
		)
		(pad "A18" thru_hole circle
			(at 30.599888 0.999998 270)
			(size 0.762 0.762)
			(drill 0.359918)
			(layers "*.Cu" "*.Mask")
			(remove_unused_layers no)
			(net "PHY_DRV_A_TO_SCC_A_17_DN")
			(clearance 0.1651)
			(thermal_gap 0.1651)
		)
		(pad "A19" thru_hole circle
			(at 32.399986 0 270)
			(size 0.762 0.762)
			(drill 0.359918)
			(layers "*.Cu" "*.Mask")
			(remove_unused_layers no)
			(net "PHY_DRV_A_TO_SCC_A_23_DN")
			(clearance 0.1651)
			(thermal_gap 0.1651)
		)
		(pad "A20" thru_hole circle
			(at 34.200084 0.999998 270)
			(size 0.762 0.762)
			(drill 0.359918)
			(layers "*.Cu" "*.Mask")
			(remove_unused_layers no)
			(net "PHY_DRV_A_TO_SCC_A_22_DN")
			(clearance 0.1651)
			(thermal_gap 0.1651)
		)
		(pad "A21" thru_hole circle
			(at 35.999928 0 270)
			(size 0.762 0.762)
			(drill 0.359918)
			(layers "*.Cu" "*.Mask")
			(remove_unused_layers no)
			(net "PHY_DRV_A_TO_SCC_A_21_DN")
			(clearance 0.1651)
			(thermal_gap 0.1651)
		)
		(pad "A22" thru_hole circle
			(at 37.800026 0.999998 270)
			(size 0.762 0.762)
			(drill 0.359918)
			(layers "*.Cu" "*.Mask")
			(remove_unused_layers no)
			(net "PHY_DRV_A_TO_SCC_A_20_DN")
			(clearance 0.1651)
			(thermal_gap 0.1651)
		)
		(pad "A23" thru_hole circle
			(at 39.600124 0 270)
			(size 0.762 0.762)
			(drill 0.359918)
			(layers "*.Cu" "*.Mask")
			(remove_unused_layers no)
			(net "PHY_DRV_A_TO_SCC_A_19_DN")
			(clearance 0.1651)
			(thermal_gap 0.1651)
		)
		(pad "A24" thru_hole circle
			(at 41.399968 0.999998 270)
			(size 0.762 0.762)
			(drill 0.359918)
			(layers "*.Cu" "*.Mask")
			(remove_unused_layers no)
			(net "PHY_DRV_A_TO_SCC_A_18_DN")
			(clearance 0.1651)
			(thermal_gap 0.1651)
		)
		(pad "A25" thru_hole circle
			(at 43.200066 0 270)
			(size 0.762 0.762)
			(drill 0.359918)
			(layers "*.Cu" "*.Mask")
			(remove_unused_layers no)
			(net "PHY_DRV_A_TO_SCC_A_24_DN")
			(clearance 0.1651)
			(thermal_gap 0.1651)
		)
		(pad "A26" thru_hole circle
			(at 44.99991 0.999998 270)
			(size 0.762 0.762)
			(drill 0.359918)
			(layers "*.Cu" "*.Mask")
			(remove_unused_layers no)
			(net "PHY_DRV_A_TO_SCC_A_25_DN")
			(clearance 0.1651)
			(thermal_gap 0.1651)
		)
		(pad "A27" thru_hole circle
			(at 46.800008 0 270)
			(size 0.762 0.762)
			(drill 0.359918)
			(layers "*.Cu" "*.Mask")
			(remove_unused_layers no)
			(net "PHY_DRV_A_TO_SCC_A_26_DN")
			(clearance 0.1651)
			(thermal_gap 0.1651)
		)
		(pad "A28" thru_hole circle
			(at 48.600106 0.999998 270)
			(size 0.762 0.762)
			(drill 0.359918)
			(layers "*.Cu" "*.Mask")
			(remove_unused_layers no)
			(net "PHY_DRV_A_TO_SCC_A_27_DN")
			(clearance 0.1651)
			(thermal_gap 0.1651)
		)
		(pad "A29" thru_hole circle
			(at 50.39995 0 270)
			(size 0.762 0.762)
			(drill 0.359918)
			(layers "*.Cu" "*.Mask")
			(remove_unused_layers no)
			(net "PHY_DRV_A_TO_SCC_A_28_DN")
			(clearance 0.1651)
			(thermal_gap 0.1651)
		)
		(pad "A30" thru_hole circle
			(at 52.200048 0.999998 270)
			(size 0.762 0.762)
			(drill 0.359918)
			(layers "*.Cu" "*.Mask")
			(remove_unused_layers no)
			(net "PHY_DRV_A_TO_SCC_A_29_DN")
			(clearance 0.1651)
			(thermal_gap 0.1651)
		)
		(pad "A31" thru_hole circle
			(at 53.999892 0 270)
			(size 0.762 0.762)
			(drill 0.359918)
			(layers "*.Cu" "*.Mask")
			(remove_unused_layers no)
			(net "PHY_DRV_A_TO_SCC_A_35_DN")
			(clearance 0.1651)
			(thermal_gap 0.1651)
		)
		(pad "A32" thru_hole circle
			(at 55.79999 0.999998 270)
			(size 0.762 0.762)
			(drill 0.359918)
			(layers "*.Cu" "*.Mask")
			(remove_unused_layers no)
			(net "PHY_DRV_A_TO_SCC_A_34_DN")
			(clearance 0.1651)
			(thermal_gap 0.1651)
		)
		(pad "A33" thru_hole circle
			(at 57.600088 0 270)
			(size 0.762 0.762)
			(drill 0.359918)
			(layers "*.Cu" "*.Mask")
			(remove_unused_layers no)
			(net "PHY_DRV_A_TO_SCC_A_33_DN")
			(clearance 0.1651)
			(thermal_gap 0.1651)
		)
		(pad "A34" thru_hole circle
			(at 59.399932 0.999998 270)
			(size 0.762 0.762)
			(drill 0.359918)
			(layers "*.Cu" "*.Mask")
			(remove_unused_layers no)
			(net "PHY_DRV_A_TO_SCC_A_32_DN")
			(clearance 0.1651)
			(thermal_gap 0.1651)
		)
		(pad "A35" thru_hole circle
			(at 61.20003 0 270)
			(size 0.762 0.762)
			(drill 0.359918)
			(layers "*.Cu" "*.Mask")
			(remove_unused_layers no)
			(net "PHY_DRV_A_TO_SCC_A_31_DN")
			(clearance 0.1651)
			(thermal_gap 0.1651)
		)
		(pad "A36" thru_hole circle
			(at 62.999874 0.999998 270)
			(size 0.762 0.762)
			(drill 0.359918)
			(layers "*.Cu" "*.Mask")
			(remove_unused_layers no)
			(net "PHY_DRV_A_TO_SCC_A_30_DN")
			(clearance 0.1651)
			(thermal_gap 0.1651)
		)
		(pad "B1" thru_hole circle
			(at 0 1.400048 270)
			(size 0.762 0.762)
			(drill 0.359918)
			(layers "*.Cu" "*.Mask")
			(remove_unused_layers no)
			(net "PHY_DRV_A_TO_SCC_A_0_DP")
			(clearance 0.1651)
			(thermal_gap 0.1651)
		)
		(pad "B2" thru_hole circle
			(at 1.800098 2.400046 270)
			(size 0.762 0.762)
			(drill 0.359918)
			(layers "*.Cu" "*.Mask")
			(remove_unused_layers no)
			(net "PHY_DRV_A_TO_SCC_A_1_DP")
			(clearance 0.1651)
			(thermal_gap 0.1651)
		)
		(pad "B3" thru_hole circle
			(at 3.599942 1.400048 270)
			(size 0.762 0.762)
			(drill 0.359918)
			(layers "*.Cu" "*.Mask")
			(remove_unused_layers no)
			(net "PHY_DRV_A_TO_SCC_A_2_DP")
			(clearance 0.1651)
			(thermal_gap 0.1651)
		)
		(pad "B4" thru_hole circle
			(at 5.40004 2.400046 270)
			(size 0.762 0.762)
			(drill 0.359918)
			(layers "*.Cu" "*.Mask")
			(remove_unused_layers no)
			(net "PHY_DRV_A_TO_SCC_A_3_DP")
			(clearance 0.1651)
			(thermal_gap 0.1651)
		)
		(pad "B5" thru_hole circle
			(at 7.199884 1.400048 270)
			(size 0.762 0.762)
			(drill 0.359918)
			(layers "*.Cu" "*.Mask")
			(remove_unused_layers no)
			(net "PHY_DRV_A_TO_SCC_A_4_DP")
			(clearance 0.1651)
			(thermal_gap 0.1651)
		)
		(pad "B6" thru_hole circle
			(at 8.999982 2.400046 270)
			(size 0.762 0.762)
			(drill 0.359918)
			(layers "*.Cu" "*.Mask")
			(remove_unused_layers no)
			(net "PHY_DRV_A_TO_SCC_A_5_DP")
			(clearance 0.1651)
			(thermal_gap 0.1651)
		)
		(pad "B7" thru_hole circle
			(at 10.80008 1.400048 270)
			(size 0.762 0.762)
			(drill 0.359918)
			(layers "*.Cu" "*.Mask")
			(remove_unused_layers no)
			(net "PHY_DRV_A_TO_SCC_A_11_DP")
			(clearance 0.1651)
			(thermal_gap 0.1651)
		)
		(pad "B8" thru_hole circle
			(at 12.599924 2.400046 270)
			(size 0.762 0.762)
			(drill 0.359918)
			(layers "*.Cu" "*.Mask")
			(remove_unused_layers no)
			(net "PHY_DRV_A_TO_SCC_A_10_DP")
			(clearance 0.1651)
			(thermal_gap 0.1651)
		)
		(pad "B9" thru_hole circle
			(at 14.400022 1.400048 270)
			(size 0.762 0.762)
			(drill 0.359918)
			(layers "*.Cu" "*.Mask")
			(remove_unused_layers no)
			(net "PHY_DRV_A_TO_SCC_A_9_DP")
			(clearance 0.1651)
			(thermal_gap 0.1651)
		)
		(pad "B10" thru_hole circle
			(at 16.20012 2.400046 270)
			(size 0.762 0.762)
			(drill 0.359918)
			(layers "*.Cu" "*.Mask")
			(remove_unused_layers no)
			(net "PHY_DRV_A_TO_SCC_A_8_DP")
			(clearance 0.1651)
			(thermal_gap 0.1651)
		)
		(pad "B11" thru_hole circle
			(at 17.999964 1.400048 270)
			(size 0.762 0.762)
			(drill 0.359918)
			(layers "*.Cu" "*.Mask")
			(remove_unused_layers no)
			(net "PHY_DRV_A_TO_SCC_A_7_DP")
			(clearance 0.1651)
			(thermal_gap 0.1651)
		)
		(pad "B12" thru_hole circle
			(at 19.800062 2.400046 270)
			(size 0.762 0.762)
			(drill 0.359918)
			(layers "*.Cu" "*.Mask")
			(remove_unused_layers no)
			(net "PHY_DRV_A_TO_SCC_A_6_DP")
			(clearance 0.1651)
			(thermal_gap 0.1651)
		)
		(pad "B13" thru_hole circle
			(at 21.599906 1.400048 270)
			(size 0.762 0.762)
			(drill 0.359918)
			(layers "*.Cu" "*.Mask")
			(remove_unused_layers no)
			(net "PHY_DRV_A_TO_SCC_A_12_DP")
			(clearance 0.1651)
			(thermal_gap 0.1651)
		)
		(pad "B14" thru_hole circle
			(at 23.400004 2.400046 270)
			(size 0.762 0.762)
			(drill 0.359918)
			(layers "*.Cu" "*.Mask")
			(remove_unused_layers no)
			(net "PHY_DRV_A_TO_SCC_A_13_DP")
			(clearance 0.1651)
			(thermal_gap 0.1651)
		)
		(pad "B15" thru_hole circle
			(at 25.200102 1.400048 270)
			(size 0.762 0.762)
			(drill 0.359918)
			(layers "*.Cu" "*.Mask")
			(remove_unused_layers no)
			(net "PHY_DRV_A_TO_SCC_A_14_DP")
			(clearance 0.1651)
			(thermal_gap 0.1651)
		)
		(pad "B16" thru_hole circle
			(at 26.999946 2.400046 270)
			(size 0.762 0.762)
			(drill 0.359918)
			(layers "*.Cu" "*.Mask")
			(remove_unused_layers no)
			(net "PHY_DRV_A_TO_SCC_A_15_DP")
			(clearance 0.1651)
			(thermal_gap 0.1651)
		)
		(pad "B17" thru_hole circle
			(at 28.800044 1.400048 270)
			(size 0.762 0.762)
			(drill 0.359918)
			(layers "*.Cu" "*.Mask")
			(remove_unused_layers no)
			(net "PHY_DRV_A_TO_SCC_A_16_DP")
			(clearance 0.1651)
			(thermal_gap 0.1651)
		)
		(pad "B18" thru_hole circle
			(at 30.599888 2.400046 270)
			(size 0.762 0.762)
			(drill 0.359918)
			(layers "*.Cu" "*.Mask")
			(remove_unused_layers no)
			(net "PHY_DRV_A_TO_SCC_A_17_DP")
			(clearance 0.1651)
			(thermal_gap 0.1651)
		)
		(pad "B19" thru_hole circle
			(at 32.399986 1.400048 270)
			(size 0.762 0.762)
			(drill 0.359918)
			(layers "*.Cu" "*.Mask")
			(remove_unused_layers no)
			(net "PHY_DRV_A_TO_SCC_A_23_DP")
			(clearance 0.1651)
			(thermal_gap 0.1651)
		)
		(pad "B20" thru_hole circle
			(at 34.200084 2.400046 270)
			(size 0.762 0.762)
			(drill 0.359918)
			(layers "*.Cu" "*.Mask")
			(remove_unused_layers no)
			(net "PHY_DRV_A_TO_SCC_A_22_DP")
			(clearance 0.1651)
			(thermal_gap 0.1651)
		)
		(pad "B21" thru_hole circle
			(at 35.999928 1.400048 270)
			(size 0.762 0.762)
			(drill 0.359918)
			(layers "*.Cu" "*.Mask")
			(remove_unused_layers no)
			(net "PHY_DRV_A_TO_SCC_A_21_DP")
			(clearance 0.1651)
			(thermal_gap 0.1651)
		)
		(pad "B22" thru_hole circle
			(at 37.800026 2.400046 270)
			(size 0.762 0.762)
			(drill 0.359918)
			(layers "*.Cu" "*.Mask")
			(remove_unused_layers no)
			(net "PHY_DRV_A_TO_SCC_A_20_DP")
			(clearance 0.1651)
			(thermal_gap 0.1651)
		)
		(pad "B23" thru_hole circle
			(at 39.600124 1.400048 270)
			(size 0.762 0.762)
			(drill 0.359918)
			(layers "*.Cu" "*.Mask")
			(remove_unused_layers no)
			(net "PHY_DRV_A_TO_SCC_A_19_DP")
			(clearance 0.1651)
			(thermal_gap 0.1651)
		)
		(pad "B24" thru_hole circle
			(at 41.399968 2.400046 270)
			(size 0.762 0.762)
			(drill 0.359918)
			(layers "*.Cu" "*.Mask")
			(remove_unused_layers no)
			(net "PHY_DRV_A_TO_SCC_A_18_DP")
			(clearance 0.1651)
			(thermal_gap 0.1651)
		)
		(pad "B25" thru_hole circle
			(at 43.200066 1.400048 270)
			(size 0.762 0.762)
			(drill 0.359918)
			(layers "*.Cu" "*.Mask")
			(remove_unused_layers no)
			(net "PHY_DRV_A_TO_SCC_A_24_DP")
			(clearance 0.1651)
			(thermal_gap 0.1651)
		)
		(pad "B26" thru_hole circle
			(at 44.99991 2.400046 270)
			(size 0.762 0.762)
			(drill 0.359918)
			(layers "*.Cu" "*.Mask")
			(remove_unused_layers no)
			(net "PHY_DRV_A_TO_SCC_A_25_DP")
			(clearance 0.1651)
			(thermal_gap 0.1651)
		)
		(pad "B27" thru_hole circle
			(at 46.800008 1.400048 270)
			(size 0.762 0.762)
			(drill 0.359918)
			(layers "*.Cu" "*.Mask")
			(remove_unused_layers no)
			(net "PHY_DRV_A_TO_SCC_A_26_DP")
			(clearance 0.1651)
			(thermal_gap 0.1651)
		)
		(pad "B28" thru_hole circle
			(at 48.600106 2.400046 270)
			(size 0.762 0.762)
			(drill 0.359918)
			(layers "*.Cu" "*.Mask")
			(remove_unused_layers no)
			(net "PHY_DRV_A_TO_SCC_A_27_DP")
			(clearance 0.1651)
			(thermal_gap 0.1651)
		)
		(pad "B29" thru_hole circle
			(at 50.39995 1.400048 270)
			(size 0.762 0.762)
			(drill 0.359918)
			(layers "*.Cu" "*.Mask")
			(remove_unused_layers no)
			(net "PHY_DRV_A_TO_SCC_A_28_DP")
			(clearance 0.1651)
			(thermal_gap 0.1651)
		)
		(pad "B30" thru_hole circle
			(at 52.200048 2.400046 270)
			(size 0.762 0.762)
			(drill 0.359918)
			(layers "*.Cu" "*.Mask")
			(remove_unused_layers no)
			(net "PHY_DRV_A_TO_SCC_A_29_DP")
			(clearance 0.1651)
			(thermal_gap 0.1651)
		)
		(pad "B31" thru_hole circle
			(at 53.999892 1.400048 270)
			(size 0.762 0.762)
			(drill 0.359918)
			(layers "*.Cu" "*.Mask")
			(remove_unused_layers no)
			(net "PHY_DRV_A_TO_SCC_A_35_DP")
			(clearance 0.1651)
			(thermal_gap 0.1651)
		)
		(pad "B32" thru_hole circle
			(at 55.79999 2.400046 270)
			(size 0.762 0.762)
			(drill 0.359918)
			(layers "*.Cu" "*.Mask")
			(remove_unused_layers no)
			(net "PHY_DRV_A_TO_SCC_A_34_DP")
			(clearance 0.1651)
			(thermal_gap 0.1651)
		)
		(pad "B33" thru_hole circle
			(at 57.600088 1.400048 270)
			(size 0.762 0.762)
			(drill 0.359918)
			(layers "*.Cu" "*.Mask")
			(remove_unused_layers no)
			(net "PHY_DRV_A_TO_SCC_A_33_DP")
			(clearance 0.1651)
			(thermal_gap 0.1651)
		)
	)
)
